FILE_TYPE = CONNECTIVITY;
{Allegro Design Entry HDL 17.2-2016 S081 (4005846) 1/11/2022}
"PAGE_NUMBER" = 35;
0"NC";
END.
